# T6G (Grand Teton) — schematic netlist excerpt (pin names and nets, part order shuffled) for the footprints in the layout excerpt that follows; sources: Cadence DE-HDL packaged netlist, KiCad conversion of 04192023_DAF0TMB3IC0_F0TG_MB_C_brd_V02_OCP.brd

R855  Q_RES  11.5K 1% EMPTY  pkg 0402LF  page 169 : A = P12V_AUX_DSC_VOL ; B = GND
R3285  Q_RES  68K 1% EMPTY  pkg 0402LF  page 111 : A = FM_P2E_SWB ; B = GND

(kicad_pcb
	(version 20260206)
	(generator "pcbnew")
	(generator_version "10.0")
	(general
		(thickness 1.6)
		(legacy_teardrops no)
	)
	(paper "A4")
	(title_block
		(title "04192023_DAF0TMB3IC0_F0TG_MB_C_brd_V02_OCP.brd")
		(comment 1 "Grand Teton / footprints 2426-2427 of 8354")
	)
	(layers
		(0 "F.Cu" signal "TOP")
		(4 "In1.Cu" signal "GND")
		(6 "In2.Cu" signal "IN1")
		(8 "In3.Cu" signal "GND1")
		(10 "In4.Cu" signal "IN2")
		(12 "In5.Cu" signal "GND2")
		(14 "In6.Cu" signal "IN3")
		(16 "In7.Cu" signal "GND3")
		(18 "In8.Cu" signal "VCC")
		(20 "In9.Cu" signal "VCC1")
		(22 "In10.Cu" signal "GND4")
		(24 "In11.Cu" signal "IN4")
		(26 "In12.Cu" signal "GND5")
		(28 "In13.Cu" signal "IN5")
		(30 "In14.Cu" signal "GND6")
		(32 "In15.Cu" signal "IN6")
		(34 "In16.Cu" signal "GND7")
		(2 "B.Cu" signal "BOTTOM")
		(9 "F.Adhes" user "F.Adhesive")
		(11 "B.Adhes" user "B.Adhesive")
		(13 "F.Paste" user "Package Geometry/Pastemask Top")
		(15 "B.Paste" user "Package Geometry/Pastemask Bottom")
		(5 "F.SilkS" user "Ref Des/Silkscreen Top")
		(7 "B.SilkS" user "Ref Des/Silkscreen Bottom")
		(1 "F.Mask" user "Board Geometry/Soldermask Top")
		(3 "B.Mask" user "Board Geometry/Soldermask Bottom")
		(17 "Dwgs.User" user "User.Drawings")
		(19 "Cmts.User" user "User.Comments")
		(21 "Eco1.User" user "User.Eco1")
		(23 "Eco2.User" user "User.Eco2")
		(25 "Edge.Cuts" user "Board Geometry/Outline")
		(27 "Margin" user)
		(31 "F.CrtYd" user "Package Geometry/Place Bound Top")
		(29 "B.CrtYd" user "Package Geometry/Place Bound Bottom")
		(35 "F.Fab" user "Ref Des/Assembly Top")
		(33 "B.Fab" user "Ref Des/Assembly Bottom")
	)
	(footprint ""
		(layer "F.Cu")
		(at 36.411662 -429.790098 90)
		(property "Reference" "R3285"
			(at 0 0 90)
			(layer "F.SilkS")
			(hide yes)
			(effects
				(font
					(size 1.27 1.27)
				)
			)
		)
		(property "Value" ""
			(at 0 0 90)
			(layer "F.Fab")
			(effects
				(font
					(size 1.27 1.27)
				)
			)
		)
		(duplicate_pad_numbers_are_jumpers no)
		(fp_line
			(start 0.7874 -0.4064)
			(end 0.7874 0.4064)
			(stroke
				(width 0.1524)
				(type default)
			)
			(layer "F.SilkS")
		)
		(fp_line
			(start -0.7874 -0.4064)
			(end 0.7874 -0.4064)
			(stroke
				(width 0.1524)
				(type default)
			)
			(layer "F.SilkS")
		)
		(fp_line
			(start 0.7874 0.4064)
			(end -0.7874 0.4064)
			(stroke
				(width 0.1524)
				(type default)
			)
			(layer "F.SilkS")
		)
		(fp_line
			(start -0.7874 0.4064)
			(end -0.7874 -0.4064)
			(stroke
				(width 0.1524)
				(type default)
			)
			(layer "F.SilkS")
		)
		(fp_line
			(start -0.12065 -0.305054)
			(end -0.12065 -0.2794)
			(stroke
				(width 0.1)
				(type default)
			)
			(layer "F.Fab")
		)
		(fp_line
			(start -0.67945 -0.305054)
			(end -0.12065 -0.305054)
			(stroke
				(width 0.1)
				(type default)
			)
			(layer "F.Fab")
		)
		(fp_line
			(start 0.67945 -0.3048)
			(end 0.67945 0.3048)
			(stroke
				(width 0.1)
				(type default)
			)
			(layer "F.Fab")
		)
		(fp_line
			(start 0.12065 -0.3048)
			(end 0.67945 -0.3048)
			(stroke
				(width 0.1)
				(type default)
			)
			(layer "F.Fab")
		)
		(fp_line
			(start 0.12065 -0.2794)
			(end 0.12065 -0.3048)
			(stroke
				(width 0.1)
				(type default)
			)
			(layer "F.Fab")
		)
		(fp_line
			(start -0.12065 -0.2794)
			(end 0.12065 -0.2794)
			(stroke
				(width 0.1)
				(type default)
			)
			(layer "F.Fab")
		)
		(fp_line
			(start 0.120396 0.2794)
			(end -0.12065 0.2794)
			(stroke
				(width 0.1)
				(type default)
			)
			(layer "F.Fab")
		)
		(fp_line
			(start -0.12065 0.2794)
			(end -0.12065 0.3048)
			(stroke
				(width 0.1)
				(type default)
			)
			(layer "F.Fab")
		)
		(fp_line
			(start 0.67945 0.3048)
			(end 0.120396 0.3048)
			(stroke
				(width 0.1)
				(type default)
			)
			(layer "F.Fab")
		)
		(fp_line
			(start 0.120396 0.3048)
			(end 0.120396 0.2794)
			(stroke
				(width 0.1)
				(type default)
			)
			(layer "F.Fab")
		)
		(fp_line
			(start -0.12065 0.3048)
			(end -0.67945 0.3048)
			(stroke
				(width 0.1)
				(type default)
			)
			(layer "F.Fab")
		)
		(fp_line
			(start -0.67945 0.3048)
			(end -0.67945 -0.305054)
			(stroke
				(width 0.1)
				(type default)
			)
			(layer "F.Fab")
		)
		(pad "1" smd circle
			(at -0.40005 0 90)
			(size 0 0)
			(layers "F.Cu" "F.Mask" "F.Paste")
			(net "FM_P2E_SWB")
		)
		(pad "2" smd circle
			(at 0.40005 0 90)
			(size 0 0)
			(layers "F.Cu" "F.Mask" "F.Paste")
			(net "GND")
		)
	)
	(footprint ""
		(layer "F.Cu")
		(at 43.14444 -101.74224)
		(property "Reference" "R855"
			(at 0 0 0)
			(layer "F.SilkS")
			(hide yes)
			(effects
				(font
					(size 1.27 1.27)
				)
			)
		)
		(property "Value" ""
			(at 0 0 0)
			(layer "F.Fab")
			(effects
				(font
					(size 1.27 1.27)
				)
			)
		)
		(duplicate_pad_numbers_are_jumpers no)
		(fp_line
			(start -0.7874 -0.4064)
			(end 0.7874 -0.4064)
			(stroke
				(width 0.1524)
				(type default)
			)
			(layer "F.SilkS")
		)
		(fp_line
			(start -0.7874 0.4064)
			(end -0.7874 -0.4064)
			(stroke
				(width 0.1524)
				(type default)
			)
			(layer "F.SilkS")
		)
		(fp_line
			(start 0.7874 -0.4064)
			(end 0.7874 0.4064)
			(stroke
				(width 0.1524)
				(type default)
			)
			(layer "F.SilkS")
		)
		(fp_line
			(start 0.7874 0.4064)
			(end -0.7874 0.4064)
			(stroke
				(width 0.1524)
				(type default)
			)
			(layer "F.SilkS")
		)
		(fp_line
			(start -0.67945 -0.305054)
			(end -0.12065 -0.305054)
			(stroke
				(width 0.1)
				(type default)
			)
			(layer "F.Fab")
		)
		(fp_line
			(start -0.67945 0.3048)
			(end -0.67945 -0.305054)
			(stroke
				(width 0.1)
				(type default)
			)
			(layer "F.Fab")
		)
		(fp_line
			(start -0.12065 -0.305054)
			(end -0.12065 -0.2794)
			(stroke
				(width 0.1)
				(type default)
			)
			(layer "F.Fab")
		)
		(fp_line
			(start -0.12065 -0.2794)
			(end 0.12065 -0.2794)
			(stroke
				(width 0.1)
				(type default)
			)
			(layer "F.Fab")
		)
		(fp_line
			(start -0.12065 0.2794)
			(end -0.12065 0.3048)
			(stroke
				(width 0.1)
				(type default)
			)
			(layer "F.Fab")
		)
		(fp_line
			(start -0.12065 0.3048)
			(end -0.67945 0.3048)
			(stroke
				(width 0.1)
				(type default)
			)
			(layer "F.Fab")
		)
		(fp_line
			(start 0.120396 0.2794)
			(end -0.12065 0.2794)
			(stroke
				(width 0.1)
				(type default)
			)
			(layer "F.Fab")
		)
		(fp_line
			(start 0.120396 0.3048)
			(end 0.120396 0.2794)
			(stroke
				(width 0.1)
				(type default)
			)
			(layer "F.Fab")
		)
		(fp_line
			(start 0.12065 -0.3048)
			(end 0.67945 -0.3048)
			(stroke
				(width 0.1)
				(type default)
			)
			(layer "F.Fab")
		)
		(fp_line
			(start 0.12065 -0.2794)
			(end 0.12065 -0.3048)
			(stroke
				(width 0.1)
				(type default)
			)
			(layer "F.Fab")
		)
		(fp_line
			(start 0.67945 -0.3048)
			(end 0.67945 0.3048)
			(stroke
				(width 0.1)
				(type default)
			)
			(layer "F.Fab")
		)
		(fp_line
			(start 0.67945 0.3048)
			(end 0.120396 0.3048)
			(stroke
				(width 0.1)
				(type default)
			)
			(layer "F.Fab")
		)
		(pad "1" smd circle
			(at -0.40005 0)
			(size 0 0)
			(layers "F.Cu" "F.Mask" "F.Paste")
			(net "P12V_AUX_DSC_VOL")
		)
		(pad "2" smd circle
			(at 0.40005 0)
			(size 0 0)
			(layers "F.Cu" "F.Mask" "F.Paste")
			(net "GND")
		)
	)
)
